(kicad_pcb
	(version 20260206)
	(generator "pcbnew")
	(generator_version "10.0")
	(general
		(thickness 1.6)
		(legacy_teardrops no)
	)
	(paper "A4")
	(title_block
		(title "peb — Lightning_PEB_BRD.brd")
		(comment 1 "Lightning (Wiwynn / Facebook NVMe JBOF) / footprint 1585 of 2563 (U40), pads 347-408 of 408")
	)
	(layers
		(0 "F.Cu" signal "TOP")
		(4 "In1.Cu" signal "L2GND")
		(6 "In2.Cu" signal "L3")
		(8 "In3.Cu" signal "L4VCC")
		(10 "In4.Cu" signal "L5VCC")
		(12 "In5.Cu" signal "L6")
		(14 "In6.Cu" signal "L7GND")
		(2 "B.Cu" signal "BOTTOM")
		(9 "F.Adhes" user "F.Adhesive")
		(11 "B.Adhes" user "B.Adhesive")
		(13 "F.Paste" user "Package Geometry/Pastemask Top")
		(15 "B.Paste" user "Package Geometry/Pastemask Bottom")
		(5 "F.SilkS" user "Ref Des/Silkscreen Top")
		(7 "B.SilkS" user "Ref Des/Silkscreen Bottom")
		(1 "F.Mask" user "Board Geometry/Soldermask Top")
		(3 "B.Mask" user "Board Geometry/Soldermask Bottom")
		(17 "Dwgs.User" user "User.Drawings")
		(19 "Cmts.User" user "User.Comments")
		(21 "Eco1.User" user "User.Eco1")
		(23 "Eco2.User" user "User.Eco2")
		(25 "Edge.Cuts" user "Board Geometry/Outline")
		(27 "Margin" user)
		(31 "F.CrtYd" user "Package Geometry/Place Bound Top")
		(29 "B.CrtYd" user "Package Geometry/Place Bound Bottom")
		(35 "F.Fab" user "Ref Des/Assembly Top")
		(33 "B.Fab" user "Ref Des/Assembly Bottom")
	)
	(footprint ""
		(layer "F.Cu")
		(at 38.104826 -130.48488 180)
		(property "Reference" "U40"
			(at 0 0 180)
			(layer "F.SilkS")
			(hide yes)
			(effects
				(font
					(size 1.27 1.27)
				)
			)
		)
		(property "Value" "AST2400A1-GP"
			(at -17.7292 -6.184392 180)
			(unlocked yes)
			(layer "F.Fab")
			(hide yes)
			(effects
				(font
					(size 1.016 1.016)
					(thickness 0.1524)
				)
			)
		)
		(property "Device Type" "BGA408D19H52"
			(at -17.7292 -7.708392 180)
			(unlocked yes)
			(layer "F.Fab")
			(hide yes)
			(effects
				(font
					(size 1.016 1.016)
					(thickness 0.1524)
				)
			)
		)
		(duplicate_pad_numbers_are_jumpers no)
		(pad "V5" smd circle
			(at -5.199888 5.199888 180)
			(size 0.3556 0.3556)
			(layers "F.Cu" "F.Mask" "F.Paste")
			(net "BMC_SSD_RST#6")
		)
		(pad "V6" smd circle
			(at -4.400042 5.199888 180)
			(size 0.3556 0.3556)
			(layers "F.Cu" "F.Mask" "F.Paste")
			(net "TP_GPIOO0")
		)
		(pad "V7" smd circle
			(at -3.599942 5.199888 180)
			(size 0.3556 0.3556)
			(layers "F.Cu" "F.Mask" "F.Paste")
			(net "TP_GPIOO7")
		)
		(pad "V8" smd circle
			(at -2.800096 5.199888 180)
			(size 0.3556 0.3556)
			(layers "F.Cu" "F.Mask" "F.Paste")
			(net "MEMDM_1")
		)
		(pad "V9" smd circle
			(at -1.999996 5.199888 180)
			(size 0.3556 0.3556)
			(layers "F.Cu" "F.Mask" "F.Paste")
			(net "MEMDQ_13")
		)
		(pad "V10" smd circle
			(at -1.199896 5.199888 180)
			(size 0.3556 0.3556)
			(layers "F.Cu" "F.Mask" "F.Paste")
			(net "MEMDQ_8")
		)
		(pad "V11" smd circle
			(at -0.40005 5.199888 180)
			(size 0.3556 0.3556)
			(layers "F.Cu" "F.Mask" "F.Paste")
			(net "MEMDQ_6")
		)
		(pad "V12" smd circle
			(at 0.40005 5.199888 180)
			(size 0.3556 0.3556)
			(layers "F.Cu" "F.Mask" "F.Paste")
			(net "MEMDQ_1")
		)
		(pad "V13" smd circle
			(at 1.199896 5.199888 180)
			(size 0.3556 0.3556)
			(layers "F.Cu" "F.Mask" "F.Paste")
			(net "DDR_VREF")
		)
		(pad "V14" smd circle
			(at 1.999996 5.199888 180)
			(size 0.3556 0.3556)
			(layers "F.Cu" "F.Mask" "F.Paste")
			(net "MEMODT")
		)
		(pad "V15" smd circle
			(at 2.800096 5.199888 180)
			(size 0.3556 0.3556)
			(layers "F.Cu" "F.Mask" "F.Paste")
			(net "MEMA_2")
		)
		(pad "V16" smd circle
			(at 3.599942 5.199888 180)
			(size 0.3556 0.3556)
			(layers "F.Cu" "F.Mask" "F.Paste")
			(net "BMC_MIOZ")
		)
		(pad "V17" smd circle
			(at 4.400042 5.199888 180)
			(size 0.3556 0.3556)
			(layers "F.Cu" "F.Mask" "F.Paste")
			(net "MPLLAV33")
		)
		(pad "V18" smd circle
			(at 5.199888 5.199888 180)
			(size 0.3556 0.3556)
			(layers "F.Cu" "F.Mask" "F.Paste")
			(net "GND")
		)
		(pad "V19" smd circle
			(at 5.999988 5.199888 180)
			(size 0.3556 0.3556)
			(layers "F.Cu" "F.Mask" "F.Paste")
			(net "P1V26_STBY")
		)
		(pad "V20" smd circle
			(at 6.800088 5.199888 180)
			(size 0.3556 0.3556)
			(layers "F.Cu" "F.Mask" "F.Paste")
			(net "FLA_CS1")
		)
		(pad "V21" smd circle
			(at 7.599934 5.199888 180)
			(size 0.3556 0.3556)
			(layers "F.Cu" "F.Mask" "F.Paste")
			(net "GPIOR4_BMC_INT_N_R")
		)
		(pad "V22" smd circle
			(at 8.400034 5.199888 180)
			(size 0.3556 0.3556)
			(layers "F.Cu" "F.Mask" "F.Paste")
			(net "ROMD6")
		)
		(pad "W1" smd circle
			(at -8.400034 5.999988 180)
			(size 0.3556 0.3556)
			(layers "F.Cu" "F.Mask" "F.Paste")
			(net "CBL_PRSNT_N_7")
		)
		(pad "W2" smd circle
			(at -7.599934 5.999988 180)
			(size 0.3556 0.3556)
			(layers "F.Cu" "F.Mask" "F.Paste")
			(net "BMC_SSD_RST#0")
		)
		(pad "W3" smd circle
			(at -6.800088 5.999988 180)
			(size 0.3556 0.3556)
			(layers "F.Cu" "F.Mask" "F.Paste")
			(net "BMC_SSD_RST#3")
		)
		(pad "W4" smd circle
			(at -5.999988 5.999988 180)
			(size 0.3556 0.3556)
			(layers "F.Cu" "F.Mask" "F.Paste")
			(net "FAN_PWM_PCIE_BMC")
		)
		(pad "W5" smd circle
			(at -5.199888 5.999988 180)
			(size 0.3556 0.3556)
			(layers "F.Cu" "F.Mask" "F.Paste")
			(net "BMC_SELF_TRAY_R")
		)
		(pad "W6" smd circle
			(at -4.400042 5.999988 180)
			(size 0.3556 0.3556)
			(layers "F.Cu" "F.Mask" "F.Paste")
			(net "TP_GPIOO4")
		)
		(pad "W7" smd circle
			(at -3.599942 5.999988 180)
			(size 0.3556 0.3556)
			(layers "F.Cu" "F.Mask" "F.Paste")
			(net "TP_GPIOP2")
		)
		(pad "W8" smd circle
			(at -2.800096 5.999988 180)
			(size 0.3556 0.3556)
			(layers "F.Cu" "F.Mask" "F.Paste")
			(net "MEMDQ_15")
		)
		(pad "W9" smd circle
			(at -1.999996 5.999988 180)
			(size 0.3556 0.3556)
			(layers "F.Cu" "F.Mask" "F.Paste")
			(net "MEMDQ_12")
		)
		(pad "W10" smd circle
			(at -1.199896 5.999988 180)
			(size 0.3556 0.3556)
			(layers "F.Cu" "F.Mask" "F.Paste")
			(net "MEMDM_0")
		)
		(pad "W11" smd circle
			(at -0.40005 5.999988 180)
			(size 0.3556 0.3556)
			(layers "F.Cu" "F.Mask" "F.Paste")
			(net "MEMDQ_5")
		)
		(pad "W12" smd circle
			(at 0.40005 5.999988 180)
			(size 0.3556 0.3556)
			(layers "F.Cu" "F.Mask" "F.Paste")
			(net "MEMDQ_0")
		)
		(pad "W13" smd circle
			(at 1.199896 5.999988 180)
			(size 0.3556 0.3556)
			(layers "F.Cu" "F.Mask" "F.Paste")
			(net "MEMRASN")
		)
		(pad "W14" smd circle
			(at 1.999996 5.999988 180)
			(size 0.3556 0.3556)
			(layers "F.Cu" "F.Mask" "F.Paste")
			(net "MEMBA_0")
		)
		(pad "W15" smd circle
			(at 2.800096 5.999988 180)
			(size 0.3556 0.3556)
			(layers "F.Cu" "F.Mask" "F.Paste")
			(net "MEMA_1")
		)
		(pad "W16" smd circle
			(at 3.599942 5.999988 180)
			(size 0.3556 0.3556)
			(layers "F.Cu" "F.Mask" "F.Paste")
			(net "MEMA_5")
		)
		(pad "W17" smd circle
			(at 4.400042 5.999988 180)
			(size 0.3556 0.3556)
			(layers "F.Cu" "F.Mask" "F.Paste")
			(net "MEMA_12")
		)
		(pad "W18" smd circle
			(at 5.199888 5.999988 180)
			(size 0.3556 0.3556)
			(layers "F.Cu" "F.Mask" "F.Paste")
			(net "P3V3_STBY")
		)
		(pad "W19" smd circle
			(at 5.999988 5.999988 180)
			(size 0.3556 0.3556)
			(layers "F.Cu" "F.Mask" "F.Paste")
			(net "V1PLLAV12")
		)
		(pad "W20" smd circle
			(at 6.800088 5.999988 180)
			(size 0.3556 0.3556)
			(layers "F.Cu" "F.Mask" "F.Paste")
			(net "BMC0_SRST_N")
		)
		(pad "W21" smd circle
			(at 7.599934 5.999988 180)
			(size 0.3556 0.3556)
			(layers "F.Cu" "F.Mask" "F.Paste")
			(net "GPIOR1_R")
		)
		(pad "W22" smd circle
			(at 8.400034 5.999988 180)
			(size 0.3556 0.3556)
			(layers "F.Cu" "F.Mask" "F.Paste")
			(net "GPIOR5_R")
		)
		(pad "Y1" smd circle
			(at -8.400034 6.800088 180)
			(size 0.4064 0.4064)
			(layers "F.Cu" "F.Mask" "F.Paste")
			(net "BMC_SSD_RST#1")
		)
		(pad "Y2" smd circle
			(at -7.599934 6.800088 180)
			(size 0.4064 0.4064)
			(layers "F.Cu" "F.Mask" "F.Paste")
			(net "BMC_SSD_RST#4")
		)
		(pad "Y3" smd circle
			(at -6.800088 6.800088 180)
			(size 0.4064 0.4064)
			(layers "F.Cu" "F.Mask" "F.Paste")
			(net "BMC_FW_DET_BOARD_VER_0")
		)
		(pad "Y4" smd circle
			(at -5.999988 6.800088 180)
			(size 0.3556 0.3556)
			(layers "F.Cu" "F.Mask" "F.Paste")
			(net "TP_GPION5")
		)
		(pad "Y5" smd circle
			(at -5.199888 6.800088 180)
			(size 0.3556 0.3556)
			(layers "F.Cu" "F.Mask" "F.Paste")
			(net "TP_GPIOO1")
		)
		(pad "Y6" smd circle
			(at -4.400042 6.800088 180)
			(size 0.3556 0.3556)
			(layers "F.Cu" "F.Mask" "F.Paste")
			(net "TP_GPIOP0")
		)
		(pad "Y7" smd circle
			(at -3.599942 6.800088 180)
			(size 0.3556 0.3556)
			(layers "F.Cu" "F.Mask" "F.Paste")
			(net "BMC0_TACH13")
		)
		(pad "Y8" smd circle
			(at -2.800096 6.800088 180)
			(size 0.3556 0.3556)
			(layers "F.Cu" "F.Mask" "F.Paste")
			(net "MEMDQ_14")
		)
		(pad "Y9" smd circle
			(at -1.999996 6.800088 180)
			(size 0.3556 0.3556)
			(layers "F.Cu" "F.Mask" "F.Paste")
			(net "MEMDQ_11")
		)
		(pad "Y10" smd circle
			(at -1.199896 6.800088 180)
			(size 0.3556 0.3556)
			(layers "F.Cu" "F.Mask" "F.Paste")
			(net "MEMDQ_7")
		)
		(pad "Y11" smd circle
			(at -0.40005 6.800088 180)
			(size 0.3556 0.3556)
			(layers "F.Cu" "F.Mask" "F.Paste")
			(net "MEMDQ_4")
		)
		(pad "Y12" smd circle
			(at 0.40005 6.800088 180)
			(size 0.3556 0.3556)
			(layers "F.Cu" "F.Mask" "F.Paste")
			(net "MEMCKE")
		)
		(pad "Y13" smd circle
			(at 1.199896 6.800088 180)
			(size 0.3556 0.3556)
			(layers "F.Cu" "F.Mask" "F.Paste")
			(net "MEMWEN")
		)
		(pad "Y14" smd circle
			(at 1.999996 6.800088 180)
			(size 0.3556 0.3556)
			(layers "F.Cu" "F.Mask" "F.Paste")
			(net "MEMBA_2")
		)
		(pad "Y15" smd circle
			(at 2.800096 6.800088 180)
			(size 0.3556 0.3556)
			(layers "F.Cu" "F.Mask" "F.Paste")
			(net "MEMA_10")
		)
		(pad "Y16" smd circle
			(at 3.599942 6.800088 180)
			(size 0.3556 0.3556)
			(layers "F.Cu" "F.Mask" "F.Paste")
			(net "MEMA_3")
		)
		(pad "Y17" smd circle
			(at 4.400042 6.800088 180)
			(size 0.3556 0.3556)
			(layers "F.Cu" "F.Mask" "F.Paste")
			(net "MEMA_13")
		)
		(pad "Y18" smd circle
			(at 5.199888 6.800088 180)
			(size 0.3556 0.3556)
			(layers "F.Cu" "F.Mask" "F.Paste")
			(net "P1V26_STBY")
		)
		(pad "Y19" smd circle
			(at 5.999988 6.800088 180)
			(size 0.3556 0.3556)
			(layers "F.Cu" "F.Mask" "F.Paste")
			(net "GND")
		)
		(pad "Y20" smd circle
			(at 6.800088 6.800088 180)
			(size 0.4064 0.4064)
			(layers "F.Cu" "F.Mask" "F.Paste")
			(net "V1PLLAV12")
		)
		(pad "Y21" smd circle
			(at 7.599934 6.800088 180)
			(size 0.4064 0.4064)
			(layers "F.Cu" "F.Mask" "F.Paste")
			(net "BMC_SELF_HW_RST_R")
		)
		(pad "Y22" smd circle
			(at 8.400034 6.800088 180)
			(size 0.4064 0.4064)
			(layers "F.Cu" "F.Mask" "F.Paste")
			(net "GPIOR2_R")
		)
	)
)
